(kicad_pcb
	(version 20260206)
	(generator "pcbnew")
	(generator_version "10.0")
	(general
		(thickness 1.6)
		(legacy_teardrops no)
	)
	(paper "A4")
	(title_block
		(title "03242023_DA0F0TMBIJ0_F0T_Motherboard_J_brd_V01_OCP.brd")
		(comment 1 "Grand Teton / footprints 3933-3939 of 6105")
	)
	(layers
		(0 "F.Cu" signal "TOP")
		(4 "In1.Cu" signal "GND")
		(6 "In2.Cu" signal "IN1")
		(8 "In3.Cu" signal "GND1")
		(10 "In4.Cu" signal "IN2")
		(12 "In5.Cu" signal "GND2")
		(14 "In6.Cu" signal "IN3")
		(16 "In7.Cu" signal "GND3")
		(18 "In8.Cu" signal "VCC")
		(20 "In9.Cu" signal "VCC1")
		(22 "In10.Cu" signal "GND4")
		(24 "In11.Cu" signal "IN4")
		(26 "In12.Cu" signal "GND5")
		(28 "In13.Cu" signal "IN5")
		(30 "In14.Cu" signal "GND6")
		(32 "In15.Cu" signal "IN6")
		(34 "In16.Cu" signal "GND7")
		(2 "B.Cu" signal "BOTTOM")
		(9 "F.Adhes" user "F.Adhesive")
		(11 "B.Adhes" user "B.Adhesive")
		(13 "F.Paste" user "Package Geometry/Pastemask Top")
		(15 "B.Paste" user "Package Geometry/Pastemask Bottom")
		(5 "F.SilkS" user "Ref Des/Silkscreen Top")
		(7 "B.SilkS" user "Ref Des/Silkscreen Bottom")
		(1 "F.Mask" user "Board Geometry/Soldermask Top")
		(3 "B.Mask" user "Board Geometry/Soldermask Bottom")
		(17 "Dwgs.User" user "User.Drawings")
		(19 "Cmts.User" user "User.Comments")
		(21 "Eco1.User" user "User.Eco1")
		(23 "Eco2.User" user "User.Eco2")
		(25 "Edge.Cuts" user "Board Geometry/Outline")
		(27 "Margin" user)
		(31 "F.CrtYd" user "Package Geometry/Place Bound Top")
		(29 "B.CrtYd" user "Package Geometry/Place Bound Bottom")
		(35 "F.Fab" user "Ref Des/Assembly Top")
		(33 "B.Fab" user "Ref Des/Assembly Bottom")
	)
	(footprint ""
		(layer "F.Cu")
		(at 114.91722 -294.01008)
		(property "Reference" "C235"
			(at 0 0 0)
			(layer "F.SilkS")
			(hide yes)
			(effects
				(font
					(size 1.27 1.27)
				)
			)
		)
		(property "Value" ""
			(at 0 0 0)
			(layer "F.Fab")
			(effects
				(font
					(size 1.27 1.27)
				)
			)
		)
		(duplicate_pad_numbers_are_jumpers no)
		(fp_line
			(start -1.524 -0.762)
			(end 1.524 -0.762)
			(stroke
				(width 0.1524)
				(type default)
			)
			(layer "F.SilkS")
		)
		(fp_line
			(start -1.524 0.762)
			(end -1.524 -0.762)
			(stroke
				(width 0.1524)
				(type default)
			)
			(layer "F.SilkS")
		)
		(fp_line
			(start 1.524 -0.762)
			(end 1.524 0.762)
			(stroke
				(width 0.1524)
				(type default)
			)
			(layer "F.SilkS")
		)
		(fp_line
			(start 1.524 0.762)
			(end -1.524 0.762)
			(stroke
				(width 0.1524)
				(type default)
			)
			(layer "F.SilkS")
		)
		(fp_line
			(start -1.1049 -0.724916)
			(end -1.1049 0.724916)
			(stroke
				(width 0.1)
				(type default)
			)
			(layer "F.Fab")
		)
		(fp_line
			(start -1.1049 0.724916)
			(end 1.1049 0.724916)
			(stroke
				(width 0.1)
				(type default)
			)
			(layer "F.Fab")
		)
		(fp_line
			(start 1.1049 -0.724916)
			(end -1.1049 -0.724916)
			(stroke
				(width 0.1)
				(type default)
			)
			(layer "F.Fab")
		)
		(fp_line
			(start 1.1049 0.724916)
			(end 1.1049 -0.724916)
			(stroke
				(width 0.1)
				(type default)
			)
			(layer "F.Fab")
		)
		(pad "1" smd rect
			(at -0.889 0 180)
			(size 1.016 1.27)
			(layers "F.Cu" "F.Mask" "F.Paste")
			(net "PVCCIN_CPU1")
		)
		(pad "2" smd rect
			(at 0.889 0 180)
			(size 1.016 1.27)
			(layers "F.Cu" "F.Mask" "F.Paste")
			(net "GND")
		)
	)
	(footprint ""
		(layer "F.Cu")
		(at 432.636676 -93.922342)
		(property "Reference" "R3602"
			(at 0 0 0)
			(layer "F.SilkS")
			(hide yes)
			(effects
				(font
					(size 1.27 1.27)
				)
			)
		)
		(property "Value" ""
			(at 0 0 0)
			(layer "F.Fab")
			(effects
				(font
					(size 1.27 1.27)
				)
			)
		)
		(duplicate_pad_numbers_are_jumpers no)
		(fp_line
			(start -0.7874 -0.4064)
			(end 0.7874 -0.4064)
			(stroke
				(width 0.1524)
				(type default)
			)
			(layer "F.SilkS")
		)
		(fp_line
			(start -0.7874 0.4064)
			(end -0.7874 -0.4064)
			(stroke
				(width 0.1524)
				(type default)
			)
			(layer "F.SilkS")
		)
		(fp_line
			(start 0.7874 -0.4064)
			(end 0.7874 0.4064)
			(stroke
				(width 0.1524)
				(type default)
			)
			(layer "F.SilkS")
		)
		(fp_line
			(start 0.7874 0.4064)
			(end -0.7874 0.4064)
			(stroke
				(width 0.1524)
				(type default)
			)
			(layer "F.SilkS")
		)
		(fp_line
			(start -0.67945 -0.305054)
			(end -0.12065 -0.305054)
			(stroke
				(width 0.1)
				(type default)
			)
			(layer "F.Fab")
		)
		(fp_line
			(start -0.67945 0.3048)
			(end -0.67945 -0.305054)
			(stroke
				(width 0.1)
				(type default)
			)
			(layer "F.Fab")
		)
		(fp_line
			(start -0.12065 -0.305054)
			(end -0.12065 -0.2794)
			(stroke
				(width 0.1)
				(type default)
			)
			(layer "F.Fab")
		)
		(fp_line
			(start -0.12065 -0.2794)
			(end 0.12065 -0.2794)
			(stroke
				(width 0.1)
				(type default)
			)
			(layer "F.Fab")
		)
		(fp_line
			(start -0.12065 0.2794)
			(end -0.12065 0.3048)
			(stroke
				(width 0.1)
				(type default)
			)
			(layer "F.Fab")
		)
		(fp_line
			(start -0.12065 0.3048)
			(end -0.67945 0.3048)
			(stroke
				(width 0.1)
				(type default)
			)
			(layer "F.Fab")
		)
		(fp_line
			(start 0.120396 0.2794)
			(end -0.12065 0.2794)
			(stroke
				(width 0.1)
				(type default)
			)
			(layer "F.Fab")
		)
		(fp_line
			(start 0.120396 0.3048)
			(end 0.120396 0.2794)
			(stroke
				(width 0.1)
				(type default)
			)
			(layer "F.Fab")
		)
		(fp_line
			(start 0.12065 -0.3048)
			(end 0.67945 -0.3048)
			(stroke
				(width 0.1)
				(type default)
			)
			(layer "F.Fab")
		)
		(fp_line
			(start 0.12065 -0.2794)
			(end 0.12065 -0.3048)
			(stroke
				(width 0.1)
				(type default)
			)
			(layer "F.Fab")
		)
		(fp_line
			(start 0.67945 -0.3048)
			(end 0.67945 0.3048)
			(stroke
				(width 0.1)
				(type default)
			)
			(layer "F.Fab")
		)
		(fp_line
			(start 0.67945 0.3048)
			(end 0.120396 0.3048)
			(stroke
				(width 0.1)
				(type default)
			)
			(layer "F.Fab")
		)
		(pad "1" smd circle
			(at -0.40005 0)
			(size 0 0)
			(layers "F.Cu" "F.Mask" "F.Paste")
			(net "P3V3_OCP_SFF_R")
		)
		(pad "2" smd circle
			(at 0.40005 0)
			(size 0 0)
			(layers "F.Cu" "F.Mask" "F.Paste")
			(net "VSENSE_P3V3_INA230_1_INP")
		)
	)
	(footprint ""
		(layer "F.Cu")
		(at 219.974922 -73.484994 180)
		(property "Reference" "PC2210"
			(at 0 0 180)
			(layer "F.SilkS")
			(hide yes)
			(effects
				(font
					(size 1.27 1.27)
				)
			)
		)
		(property "Value" ""
			(at 0 0 180)
			(layer "F.Fab")
			(effects
				(font
					(size 1.27 1.27)
				)
			)
		)
		(duplicate_pad_numbers_are_jumpers no)
		(fp_line
			(start 0.7874 0.4064)
			(end -0.7874 0.4064)
			(stroke
				(width 0.1524)
				(type default)
			)
			(layer "F.SilkS")
		)
		(fp_line
			(start 0.7874 -0.4064)
			(end 0.7874 0.4064)
			(stroke
				(width 0.1524)
				(type default)
			)
			(layer "F.SilkS")
		)
		(fp_line
			(start -0.7874 0.4064)
			(end -0.7874 -0.4064)
			(stroke
				(width 0.1524)
				(type default)
			)
			(layer "F.SilkS")
		)
		(fp_line
			(start -0.7874 -0.4064)
			(end 0.7874 -0.4064)
			(stroke
				(width 0.1524)
				(type default)
			)
			(layer "F.SilkS")
		)
		(fp_line
			(start 0.67945 0.3048)
			(end 0.120396 0.3048)
			(stroke
				(width 0.1)
				(type default)
			)
			(layer "F.Fab")
		)
		(fp_line
			(start 0.67945 -0.3048)
			(end 0.67945 0.3048)
			(stroke
				(width 0.1)
				(type default)
			)
			(layer "F.Fab")
		)
		(fp_line
			(start 0.12065 -0.2794)
			(end 0.12065 -0.3048)
			(stroke
				(width 0.1)
				(type default)
			)
			(layer "F.Fab")
		)
		(fp_line
			(start 0.12065 -0.3048)
			(end 0.67945 -0.3048)
			(stroke
				(width 0.1)
				(type default)
			)
			(layer "F.Fab")
		)
		(fp_line
			(start 0.120396 0.3048)
			(end 0.120396 0.2794)
			(stroke
				(width 0.1)
				(type default)
			)
			(layer "F.Fab")
		)
		(fp_line
			(start 0.120396 0.2794)
			(end -0.12065 0.2794)
			(stroke
				(width 0.1)
				(type default)
			)
			(layer "F.Fab")
		)
		(fp_line
			(start -0.12065 0.3048)
			(end -0.67945 0.3048)
			(stroke
				(width 0.1)
				(type default)
			)
			(layer "F.Fab")
		)
		(fp_line
			(start -0.12065 0.2794)
			(end -0.12065 0.3048)
			(stroke
				(width 0.1)
				(type default)
			)
			(layer "F.Fab")
		)
		(fp_line
			(start -0.12065 -0.2794)
			(end 0.12065 -0.2794)
			(stroke
				(width 0.1)
				(type default)
			)
			(layer "F.Fab")
		)
		(fp_line
			(start -0.12065 -0.305054)
			(end -0.12065 -0.2794)
			(stroke
				(width 0.1)
				(type default)
			)
			(layer "F.Fab")
		)
		(fp_line
			(start -0.67945 0.3048)
			(end -0.67945 -0.305054)
			(stroke
				(width 0.1)
				(type default)
			)
			(layer "F.Fab")
		)
		(fp_line
			(start -0.67945 -0.305054)
			(end -0.12065 -0.305054)
			(stroke
				(width 0.1)
				(type default)
			)
			(layer "F.Fab")
		)
		(pad "1" smd circle
			(at -0.40005 0 180)
			(size 0 0)
			(layers "F.Cu" "F.Mask" "F.Paste")
			(net "P3V3_E1S_VCC_0")
		)
		(pad "2" smd circle
			(at 0.40005 0 180)
			(size 0 0)
			(layers "F.Cu" "F.Mask" "F.Paste")
			(net "GND")
		)
	)
	(footprint ""
		(layer "F.Cu")
		(at 354.264214 -252.956314 -90)
		(property "Reference" "C1006"
			(at 0 0 270)
			(layer "F.SilkS")
			(hide yes)
			(effects
				(font
					(size 1.27 1.27)
				)
			)
		)
		(property "Value" ""
			(at 0 0 270)
			(layer "F.Fab")
			(effects
				(font
					(size 1.27 1.27)
				)
			)
		)
		(duplicate_pad_numbers_are_jumpers no)
		(fp_line
			(start -0.7874 0.4064)
			(end -0.7874 -0.4064)
			(stroke
				(width 0.1524)
				(type default)
			)
			(layer "F.SilkS")
		)
		(fp_line
			(start 0.7874 0.4064)
			(end -0.7874 0.4064)
			(stroke
				(width 0.1524)
				(type default)
			)
			(layer "F.SilkS")
		)
		(fp_line
			(start -0.7874 -0.4064)
			(end 0.7874 -0.4064)
			(stroke
				(width 0.1524)
				(type default)
			)
			(layer "F.SilkS")
		)
		(fp_line
			(start 0.7874 -0.4064)
			(end 0.7874 0.4064)
			(stroke
				(width 0.1524)
				(type default)
			)
			(layer "F.SilkS")
		)
		(fp_line
			(start -0.67945 0.3048)
			(end -0.67945 -0.305054)
			(stroke
				(width 0.1)
				(type default)
			)
			(layer "F.Fab")
		)
		(fp_line
			(start -0.12065 0.3048)
			(end -0.67945 0.3048)
			(stroke
				(width 0.1)
				(type default)
			)
			(layer "F.Fab")
		)
		(fp_line
			(start 0.120396 0.3048)
			(end 0.120396 0.2794)
			(stroke
				(width 0.1)
				(type default)
			)
			(layer "F.Fab")
		)
		(fp_line
			(start 0.67945 0.3048)
			(end 0.120396 0.3048)
			(stroke
				(width 0.1)
				(type default)
			)
			(layer "F.Fab")
		)
		(fp_line
			(start -0.12065 0.2794)
			(end -0.12065 0.3048)
			(stroke
				(width 0.1)
				(type default)
			)
			(layer "F.Fab")
		)
		(fp_line
			(start 0.120396 0.2794)
			(end -0.12065 0.2794)
			(stroke
				(width 0.1)
				(type default)
			)
			(layer "F.Fab")
		)
		(fp_line
			(start -0.12065 -0.2794)
			(end 0.12065 -0.2794)
			(stroke
				(width 0.1)
				(type default)
			)
			(layer "F.Fab")
		)
		(fp_line
			(start 0.12065 -0.2794)
			(end 0.12065 -0.3048)
			(stroke
				(width 0.1)
				(type default)
			)
			(layer "F.Fab")
		)
		(fp_line
			(start 0.12065 -0.3048)
			(end 0.67945 -0.3048)
			(stroke
				(width 0.1)
				(type default)
			)
			(layer "F.Fab")
		)
		(fp_line
			(start 0.67945 -0.3048)
			(end 0.67945 0.3048)
			(stroke
				(width 0.1)
				(type default)
			)
			(layer "F.Fab")
		)
		(fp_line
			(start -0.67945 -0.305054)
			(end -0.12065 -0.305054)
			(stroke
				(width 0.1)
				(type default)
			)
			(layer "F.Fab")
		)
		(fp_line
			(start -0.12065 -0.305054)
			(end -0.12065 -0.2794)
			(stroke
				(width 0.1)
				(type default)
			)
			(layer "F.Fab")
		)
		(pad "1" smd circle
			(at -0.40005 0 270)
			(size 0 0)
			(layers "F.Cu" "F.Mask" "F.Paste")
			(net "PVCCIN_CPU0")
		)
		(pad "2" smd circle
			(at 0.40005 0 270)
			(size 0 0)
			(layers "F.Cu" "F.Mask" "F.Paste")
			(net "GND")
		)
	)
	(footprint ""
		(layer "F.Cu")
		(at 302.641 -50.383948)
		(property "Reference" "C1249"
			(at 0 0 0)
			(layer "F.SilkS")
			(hide yes)
			(effects
				(font
					(size 1.27 1.27)
				)
			)
		)
		(property "Value" ""
			(at 0 0 0)
			(layer "F.Fab")
			(effects
				(font
					(size 1.27 1.27)
				)
			)
		)
		(duplicate_pad_numbers_are_jumpers no)
		(fp_line
			(start -1.524 -0.762)
			(end 1.524 -0.762)
			(stroke
				(width 0.1524)
				(type default)
			)
			(layer "F.SilkS")
		)
		(fp_line
			(start -1.524 0.762)
			(end -1.524 -0.762)
			(stroke
				(width 0.1524)
				(type default)
			)
			(layer "F.SilkS")
		)
		(fp_line
			(start 1.524 -0.762)
			(end 1.524 0.762)
			(stroke
				(width 0.1524)
				(type default)
			)
			(layer "F.SilkS")
		)
		(fp_line
			(start 1.524 0.762)
			(end -1.524 0.762)
			(stroke
				(width 0.1524)
				(type default)
			)
			(layer "F.SilkS")
		)
		(fp_line
			(start -1.1049 -0.724916)
			(end -1.1049 0.724916)
			(stroke
				(width 0.1)
				(type default)
			)
			(layer "F.Fab")
		)
		(fp_line
			(start -1.1049 0.724916)
			(end 1.1049 0.724916)
			(stroke
				(width 0.1)
				(type default)
			)
			(layer "F.Fab")
		)
		(fp_line
			(start 1.1049 -0.724916)
			(end -1.1049 -0.724916)
			(stroke
				(width 0.1)
				(type default)
			)
			(layer "F.Fab")
		)
		(fp_line
			(start 1.1049 0.724916)
			(end 1.1049 -0.724916)
			(stroke
				(width 0.1)
				(type default)
			)
			(layer "F.Fab")
		)
		(pad "1" smd rect
			(at -0.889 0 180)
			(size 1.016 1.27)
			(layers "F.Cu" "F.Mask" "F.Paste")
			(net "P1V05_PCH_AUX")
		)
		(pad "2" smd rect
			(at 0.889 0 180)
			(size 1.016 1.27)
			(layers "F.Cu" "F.Mask" "F.Paste")
			(net "GND")
		)
	)
	(footprint ""
		(layer "F.Cu")
		(at 177.9524 -93.538548 90)
		(property "Reference" "R4584"
			(at 0 0 90)
			(layer "F.SilkS")
			(hide yes)
			(effects
				(font
					(size 1.27 1.27)
				)
			)
		)
		(property "Value" ""
			(at 0 0 90)
			(layer "F.Fab")
			(effects
				(font
					(size 1.27 1.27)
				)
			)
		)
		(duplicate_pad_numbers_are_jumpers no)
		(fp_line
			(start 0.7874 -0.4064)
			(end 0.7874 0.4064)
			(stroke
				(width 0.1524)
				(type default)
			)
			(layer "F.SilkS")
		)
		(fp_line
			(start -0.7874 -0.4064)
			(end 0.7874 -0.4064)
			(stroke
				(width 0.1524)
				(type default)
			)
			(layer "F.SilkS")
		)
		(fp_line
			(start 0.7874 0.4064)
			(end -0.7874 0.4064)
			(stroke
				(width 0.1524)
				(type default)
			)
			(layer "F.SilkS")
		)
		(fp_line
			(start -0.7874 0.4064)
			(end -0.7874 -0.4064)
			(stroke
				(width 0.1524)
				(type default)
			)
			(layer "F.SilkS")
		)
		(fp_line
			(start -0.12065 -0.305054)
			(end -0.12065 -0.2794)
			(stroke
				(width 0.1)
				(type default)
			)
			(layer "F.Fab")
		)
		(fp_line
			(start -0.67945 -0.305054)
			(end -0.12065 -0.305054)
			(stroke
				(width 0.1)
				(type default)
			)
			(layer "F.Fab")
		)
		(fp_line
			(start 0.67945 -0.3048)
			(end 0.67945 0.3048)
			(stroke
				(width 0.1)
				(type default)
			)
			(layer "F.Fab")
		)
		(fp_line
			(start 0.12065 -0.3048)
			(end 0.67945 -0.3048)
			(stroke
				(width 0.1)
				(type default)
			)
			(layer "F.Fab")
		)
		(fp_line
			(start 0.12065 -0.2794)
			(end 0.12065 -0.3048)
			(stroke
				(width 0.1)
				(type default)
			)
			(layer "F.Fab")
		)
		(fp_line
			(start -0.12065 -0.2794)
			(end 0.12065 -0.2794)
			(stroke
				(width 0.1)
				(type default)
			)
			(layer "F.Fab")
		)
		(fp_line
			(start 0.120396 0.2794)
			(end -0.12065 0.2794)
			(stroke
				(width 0.1)
				(type default)
			)
			(layer "F.Fab")
		)
		(fp_line
			(start -0.12065 0.2794)
			(end -0.12065 0.3048)
			(stroke
				(width 0.1)
				(type default)
			)
			(layer "F.Fab")
		)
		(fp_line
			(start 0.67945 0.3048)
			(end 0.120396 0.3048)
			(stroke
				(width 0.1)
				(type default)
			)
			(layer "F.Fab")
		)
		(fp_line
			(start 0.120396 0.3048)
			(end 0.120396 0.2794)
			(stroke
				(width 0.1)
				(type default)
			)
			(layer "F.Fab")
		)
		(fp_line
			(start -0.12065 0.3048)
			(end -0.67945 0.3048)
			(stroke
				(width 0.1)
				(type default)
			)
			(layer "F.Fab")
		)
		(fp_line
			(start -0.67945 0.3048)
			(end -0.67945 -0.305054)
			(stroke
				(width 0.1)
				(type default)
			)
			(layer "F.Fab")
		)
		(pad "1" smd rect
			(at -0.40005 0 270)
			(size 0.4572 0.508)
			(layers "F.Cu" "F.Mask" "F.Paste")
			(net "P3V3_AUX")
		)
		(pad "2" smd rect
			(at 0.40005 0 270)
			(size 0.4572 0.508)
			(layers "F.Cu" "F.Mask" "F.Paste")
			(net "FM_BOARD_BMC_SKU_ID0")
		)
	)
	(footprint ""
		(layer "F.Cu")
		(at 413.408114 -366.66932 -90)
		(property "Reference" "PC1349"
			(at 0 0 270)
			(layer "F.SilkS")
			(hide yes)
			(effects
				(font
					(size 1.27 1.27)
				)
			)
		)
		(property "Value" ""
			(at 0 0 270)
			(layer "F.Fab")
			(effects
				(font
					(size 1.27 1.27)
				)
			)
		)
		(duplicate_pad_numbers_are_jumpers no)
		(fp_line
			(start -0.7874 0.4064)
			(end -0.7874 -0.4064)
			(stroke
				(width 0.1524)
				(type default)
			)
			(layer "F.SilkS")
		)
		(fp_line
			(start 0.7874 0.4064)
			(end -0.7874 0.4064)
			(stroke
				(width 0.1524)
				(type default)
			)
			(layer "F.SilkS")
		)
		(fp_line
			(start -0.7874 -0.4064)
			(end 0.7874 -0.4064)
			(stroke
				(width 0.1524)
				(type default)
			)
			(layer "F.SilkS")
		)
		(fp_line
			(start 0.7874 -0.4064)
			(end 0.7874 0.4064)
			(stroke
				(width 0.1524)
				(type default)
			)
			(layer "F.SilkS")
		)
		(fp_line
			(start -0.67945 0.3048)
			(end -0.67945 -0.305054)
			(stroke
				(width 0.1)
				(type default)
			)
			(layer "F.Fab")
		)
		(fp_line
			(start -0.12065 0.3048)
			(end -0.67945 0.3048)
			(stroke
				(width 0.1)
				(type default)
			)
			(layer "F.Fab")
		)
		(fp_line
			(start 0.120396 0.3048)
			(end 0.120396 0.2794)
			(stroke
				(width 0.1)
				(type default)
			)
			(layer "F.Fab")
		)
		(fp_line
			(start 0.67945 0.3048)
			(end 0.120396 0.3048)
			(stroke
				(width 0.1)
				(type default)
			)
			(layer "F.Fab")
		)
		(fp_line
			(start -0.12065 0.2794)
			(end -0.12065 0.3048)
			(stroke
				(width 0.1)
				(type default)
			)
			(layer "F.Fab")
		)
		(fp_line
			(start 0.120396 0.2794)
			(end -0.12065 0.2794)
			(stroke
				(width 0.1)
				(type default)
			)
			(layer "F.Fab")
		)
		(fp_line
			(start -0.12065 -0.2794)
			(end 0.12065 -0.2794)
			(stroke
				(width 0.1)
				(type default)
			)
			(layer "F.Fab")
		)
		(fp_line
			(start 0.12065 -0.2794)
			(end 0.12065 -0.3048)
			(stroke
				(width 0.1)
				(type default)
			)
			(layer "F.Fab")
		)
		(fp_line
			(start 0.12065 -0.3048)
			(end 0.67945 -0.3048)
			(stroke
				(width 0.1)
				(type default)
			)
			(layer "F.Fab")
		)
		(fp_line
			(start 0.67945 -0.3048)
			(end 0.67945 0.3048)
			(stroke
				(width 0.1)
				(type default)
			)
			(layer "F.Fab")
		)
		(fp_line
			(start -0.67945 -0.305054)
			(end -0.12065 -0.305054)
			(stroke
				(width 0.1)
				(type default)
			)
			(layer "F.Fab")
		)
		(fp_line
			(start -0.12065 -0.305054)
			(end -0.12065 -0.2794)
			(stroke
				(width 0.1)
				(type default)
			)
			(layer "F.Fab")
		)
		(pad "1" smd circle
			(at -0.40005 0 270)
			(size 0 0)
			(layers "F.Cu" "F.Mask" "F.Paste")
			(net "GND")
		)
		(pad "2" smd circle
			(at 0.40005 0 270)
			(size 0 0)
			(layers "F.Cu" "F.Mask" "F.Paste")
			(net "PVCCIN_CPU0_VREF")
		)
	)
)
